(kicad_pcb
	(version 20260206)
	(generator "pcbnew")
	(generator_version "10.0")
	(general
		(thickness 1.6)
		(legacy_teardrops no)
	)
	(paper "A4")
	(title_block
		(title "03242023_DA0F0TMBIJ0_F0T_Motherboard_J_brd_V01_OCP.brd")
		(comment 1 "Grand Teton / footprints 5205-5210 of 6105")
	)
	(layers
		(0 "F.Cu" signal "TOP")
		(4 "In1.Cu" signal "GND")
		(6 "In2.Cu" signal "IN1")
		(8 "In3.Cu" signal "GND1")
		(10 "In4.Cu" signal "IN2")
		(12 "In5.Cu" signal "GND2")
		(14 "In6.Cu" signal "IN3")
		(16 "In7.Cu" signal "GND3")
		(18 "In8.Cu" signal "VCC")
		(20 "In9.Cu" signal "VCC1")
		(22 "In10.Cu" signal "GND4")
		(24 "In11.Cu" signal "IN4")
		(26 "In12.Cu" signal "GND5")
		(28 "In13.Cu" signal "IN5")
		(30 "In14.Cu" signal "GND6")
		(32 "In15.Cu" signal "IN6")
		(34 "In16.Cu" signal "GND7")
		(2 "B.Cu" signal "BOTTOM")
		(9 "F.Adhes" user "F.Adhesive")
		(11 "B.Adhes" user "B.Adhesive")
		(13 "F.Paste" user "Package Geometry/Pastemask Top")
		(15 "B.Paste" user "Package Geometry/Pastemask Bottom")
		(5 "F.SilkS" user "Ref Des/Silkscreen Top")
		(7 "B.SilkS" user "Ref Des/Silkscreen Bottom")
		(1 "F.Mask" user "Board Geometry/Soldermask Top")
		(3 "B.Mask" user "Board Geometry/Soldermask Bottom")
		(17 "Dwgs.User" user "User.Drawings")
		(19 "Cmts.User" user "User.Comments")
		(21 "Eco1.User" user "User.Eco1")
		(23 "Eco2.User" user "User.Eco2")
		(25 "Edge.Cuts" user "Board Geometry/Outline")
		(27 "Margin" user)
		(31 "F.CrtYd" user "Package Geometry/Place Bound Top")
		(29 "B.CrtYd" user "Package Geometry/Place Bound Bottom")
		(35 "F.Fab" user "Ref Des/Assembly Top")
		(33 "B.Fab" user "Ref Des/Assembly Bottom")
	)
	(footprint ""
		(layer "B.Cu")
		(at 433.14874 -313.913266 180)
		(property "Reference" "D44"
			(at 2.36474 0.731012 0)
			(unlocked yes)
			(layer "B.SilkS")
			(effects
				(font
					(size 0.7874 0.5842)
					(thickness 0.1524)
				)
				(justify left mirror)
			)
		)
		(property "Value" ""
			(at 0 0 0)
			(layer "B.Fab")
			(effects
				(font
					(size 1.27 1.27)
				)
				(justify mirror)
			)
		)
		(duplicate_pad_numbers_are_jumpers no)
		(fp_line
			(start 2.050796 0.700024)
			(end 2.050796 -0.700024)
			(stroke
				(width 0.1524)
				(type default)
			)
			(layer "B.SilkS")
		)
		(fp_line
			(start 2.050796 -0.700024)
			(end -2.050796 -0.700024)
			(stroke
				(width 0.1524)
				(type default)
			)
			(layer "B.SilkS")
		)
		(fp_line
			(start 0.30607 0.500126)
			(end -0.193802 0)
			(stroke
				(width 0.1524)
				(type default)
			)
			(layer "B.SilkS")
		)
		(fp_line
			(start 0.30607 -0.500126)
			(end 0.30607 0.500126)
			(stroke
				(width 0.1524)
				(type default)
			)
			(layer "B.SilkS")
		)
		(fp_line
			(start -0.193802 0)
			(end 0.30607 -0.500126)
			(stroke
				(width 0.1524)
				(type default)
			)
			(layer "B.SilkS")
		)
		(fp_line
			(start -0.293878 -0.500126)
			(end -0.293878 0.500126)
			(stroke
				(width 0.1524)
				(type default)
			)
			(layer "B.SilkS")
		)
		(fp_line
			(start -2.050796 0.700024)
			(end 2.050796 0.700024)
			(stroke
				(width 0.1524)
				(type default)
			)
			(layer "B.SilkS")
		)
		(fp_line
			(start -2.050796 -0.700024)
			(end -2.050796 0.700024)
			(stroke
				(width 0.1524)
				(type default)
			)
			(layer "B.SilkS")
		)
		(fp_line
			(start -2.051304 0.6985)
			(end -2.051304 0.635)
			(stroke
				(width 0.1524)
				(type default)
			)
			(layer "B.SilkS")
		)
		(fp_line
			(start -2.051304 0.635)
			(end -2.152904 0.635)
			(stroke
				(width 0.1524)
				(type default)
			)
			(layer "B.SilkS")
		)
		(fp_line
			(start -2.064004 -0.6731)
			(end -2.064004 -0.6985)
			(stroke
				(width 0.1524)
				(type default)
			)
			(layer "B.SilkS")
		)
		(fp_line
			(start -2.064004 -0.6985)
			(end -2.229104 -0.6985)
			(stroke
				(width 0.1524)
				(type default)
			)
			(layer "B.SilkS")
		)
		(fp_line
			(start -2.152904 0.635)
			(end -2.152904 -0.6985)
			(stroke
				(width 0.1524)
				(type default)
			)
			(layer "B.SilkS")
		)
		(fp_line
			(start -2.152904 -0.6985)
			(end -2.343404 -0.6985)
			(stroke
				(width 0.1524)
				(type default)
			)
			(layer "B.SilkS")
		)
		(fp_line
			(start -2.229104 0.6985)
			(end -2.051304 0.6985)
			(stroke
				(width 0.1524)
				(type default)
			)
			(layer "B.SilkS")
		)
		(fp_line
			(start -2.229104 -0.6985)
			(end -2.229104 0.6985)
			(stroke
				(width 0.1524)
				(type default)
			)
			(layer "B.SilkS")
		)
		(fp_line
			(start -2.343404 0.6985)
			(end -2.216404 0.6985)
			(stroke
				(width 0.1524)
				(type default)
			)
			(layer "B.SilkS")
		)
		(fp_line
			(start -2.343404 -0.6985)
			(end -2.343404 0.6985)
			(stroke
				(width 0.1524)
				(type default)
			)
			(layer "B.SilkS")
		)
		(fp_line
			(start 0.899922 0.700024)
			(end 0.899922 -0.700024)
			(stroke
				(width 0.1)
				(type default)
			)
			(layer "B.Fab")
		)
		(fp_line
			(start 0.899922 -0.700024)
			(end -0.899922 -0.700024)
			(stroke
				(width 0.1)
				(type default)
			)
			(layer "B.Fab")
		)
		(fp_line
			(start -0.899922 0.700024)
			(end 0.899922 0.700024)
			(stroke
				(width 0.1)
				(type default)
			)
			(layer "B.Fab")
		)
		(fp_line
			(start -0.899922 -0.700024)
			(end -0.899922 0.700024)
			(stroke
				(width 0.1)
				(type default)
			)
			(layer "B.Fab")
		)
		(fp_text user "+"
			(at 3.72999 0.503682 90)
			(unlocked yes)
			(layer "B.SilkS")
			(effects
				(font
					(size 1.905 1.4224)
					(thickness 0.1524)
				)
				(justify left mirror)
			)
		)
		(fp_text user "-"
			(at -4.261104 0.10795 0)
			(unlocked yes)
			(layer "B.SilkS")
			(effects
				(font
					(size 1.905 1.4224)
					(thickness 0.1524)
				)
				(justify left mirror)
			)
		)
		(fp_text user "+"
			(at 3.123946 0.762 90)
			(unlocked yes)
			(layer "B.Fab")
			(effects
				(font
					(size 1.905 1.4224)
					(thickness 0.1524)
				)
				(justify left mirror)
			)
		)
		(fp_text user "-"
			(at -3.880104 0.23495 0)
			(unlocked yes)
			(layer "B.Fab")
			(effects
				(font
					(size 1.905 1.4224)
					(thickness 0.1524)
				)
				(justify left mirror)
			)
		)
		(pad "1" smd rect
			(at 1.199896 0 90)
			(size 0.6604 1.3716)
			(layers "B.Cu" "B.Mask" "B.Paste")
			(net "PWRGD_FAIL_CPU0_EF_R1")
		)
		(pad "2" smd rect
			(at -1.199896 0 270)
			(size 0.6604 1.3716)
			(layers "B.Cu" "B.Mask" "B.Paste")
			(net "P3V3_AUX")
		)
	)
	(footprint ""
		(layer "B.Cu")
		(at 228.114098 -117.960648 -90)
		(property "Reference" "R4517"
			(at 0 0 90)
			(layer "B.SilkS")
			(hide yes)
			(effects
				(font
					(size 1.27 1.27)
				)
				(justify mirror)
			)
		)
		(property "Value" ""
			(at 0 0 90)
			(layer "B.Fab")
			(effects
				(font
					(size 1.27 1.27)
				)
				(justify mirror)
			)
		)
		(duplicate_pad_numbers_are_jumpers no)
		(fp_line
			(start -0.7874 0.4064)
			(end 0.7874 0.4064)
			(stroke
				(width 0.1524)
				(type default)
			)
			(layer "B.SilkS")
		)
		(fp_line
			(start 0.7874 0.4064)
			(end 0.7874 -0.4064)
			(stroke
				(width 0.1524)
				(type default)
			)
			(layer "B.SilkS")
		)
		(fp_line
			(start -0.7874 -0.4064)
			(end -0.7874 0.4064)
			(stroke
				(width 0.1524)
				(type default)
			)
			(layer "B.SilkS")
		)
		(fp_line
			(start 0.7874 -0.4064)
			(end -0.7874 -0.4064)
			(stroke
				(width 0.1524)
				(type default)
			)
			(layer "B.SilkS")
		)
		(fp_line
			(start -0.67945 0.3048)
			(end -0.120396 0.3048)
			(stroke
				(width 0.1)
				(type default)
			)
			(layer "B.Fab")
		)
		(fp_line
			(start -0.120396 0.3048)
			(end -0.120396 0.2794)
			(stroke
				(width 0.1)
				(type default)
			)
			(layer "B.Fab")
		)
		(fp_line
			(start 0.12065 0.3048)
			(end 0.67945 0.3048)
			(stroke
				(width 0.1)
				(type default)
			)
			(layer "B.Fab")
		)
		(fp_line
			(start 0.67945 0.3048)
			(end 0.67945 -0.305054)
			(stroke
				(width 0.1)
				(type default)
			)
			(layer "B.Fab")
		)
		(fp_line
			(start -0.120396 0.2794)
			(end 0.12065 0.2794)
			(stroke
				(width 0.1)
				(type default)
			)
			(layer "B.Fab")
		)
		(fp_line
			(start 0.12065 0.2794)
			(end 0.12065 0.3048)
			(stroke
				(width 0.1)
				(type default)
			)
			(layer "B.Fab")
		)
		(fp_line
			(start -0.12065 -0.2794)
			(end -0.12065 -0.3048)
			(stroke
				(width 0.1)
				(type default)
			)
			(layer "B.Fab")
		)
		(fp_line
			(start 0.12065 -0.2794)
			(end -0.12065 -0.2794)
			(stroke
				(width 0.1)
				(type default)
			)
			(layer "B.Fab")
		)
		(fp_line
			(start -0.67945 -0.3048)
			(end -0.67945 0.3048)
			(stroke
				(width 0.1)
				(type default)
			)
			(layer "B.Fab")
		)
		(fp_line
			(start -0.12065 -0.3048)
			(end -0.67945 -0.3048)
			(stroke
				(width 0.1)
				(type default)
			)
			(layer "B.Fab")
		)
		(fp_line
			(start 0.12065 -0.305054)
			(end 0.12065 -0.2794)
			(stroke
				(width 0.1)
				(type default)
			)
			(layer "B.Fab")
		)
		(fp_line
			(start 0.67945 -0.305054)
			(end 0.12065 -0.305054)
			(stroke
				(width 0.1)
				(type default)
			)
			(layer "B.Fab")
		)
		(pad "1" smd circle
			(at 0.40005 0 90)
			(size 0 0)
			(layers "B.Cu" "B.Mask" "B.Paste")
			(net "P3V3")
		)
		(pad "2" smd circle
			(at -0.40005 0 90)
			(size 0 0)
			(layers "B.Cu" "B.Mask" "B.Paste")
			(net "OCP_SFF_CLK_OE_N")
		)
	)
	(footprint ""
		(layer "B.Cu")
		(at 80.35163 -52.482496 90)
		(property "Reference" "R3832"
			(at 0 0 90)
			(layer "B.SilkS")
			(hide yes)
			(effects
				(font
					(size 1.27 1.27)
				)
				(justify mirror)
			)
		)
		(property "Value" ""
			(at 0 0 90)
			(layer "B.Fab")
			(effects
				(font
					(size 1.27 1.27)
				)
				(justify mirror)
			)
		)
		(duplicate_pad_numbers_are_jumpers no)
		(fp_line
			(start 0.7874 -0.4064)
			(end -0.7874 -0.4064)
			(stroke
				(width 0.1524)
				(type default)
			)
			(layer "B.SilkS")
		)
		(fp_line
			(start -0.7874 -0.4064)
			(end -0.7874 0.4064)
			(stroke
				(width 0.1524)
				(type default)
			)
			(layer "B.SilkS")
		)
		(fp_line
			(start 0.7874 0.4064)
			(end 0.7874 -0.4064)
			(stroke
				(width 0.1524)
				(type default)
			)
			(layer "B.SilkS")
		)
		(fp_line
			(start -0.7874 0.4064)
			(end 0.7874 0.4064)
			(stroke
				(width 0.1524)
				(type default)
			)
			(layer "B.SilkS")
		)
		(fp_line
			(start 0.67945 -0.305054)
			(end 0.12065 -0.305054)
			(stroke
				(width 0.1)
				(type default)
			)
			(layer "B.Fab")
		)
		(fp_line
			(start 0.12065 -0.305054)
			(end 0.12065 -0.2794)
			(stroke
				(width 0.1)
				(type default)
			)
			(layer "B.Fab")
		)
		(fp_line
			(start -0.12065 -0.3048)
			(end -0.67945 -0.3048)
			(stroke
				(width 0.1)
				(type default)
			)
			(layer "B.Fab")
		)
		(fp_line
			(start -0.67945 -0.3048)
			(end -0.67945 0.3048)
			(stroke
				(width 0.1)
				(type default)
			)
			(layer "B.Fab")
		)
		(fp_line
			(start 0.12065 -0.2794)
			(end -0.12065 -0.2794)
			(stroke
				(width 0.1)
				(type default)
			)
			(layer "B.Fab")
		)
		(fp_line
			(start -0.12065 -0.2794)
			(end -0.12065 -0.3048)
			(stroke
				(width 0.1)
				(type default)
			)
			(layer "B.Fab")
		)
		(fp_line
			(start 0.12065 0.2794)
			(end 0.12065 0.3048)
			(stroke
				(width 0.1)
				(type default)
			)
			(layer "B.Fab")
		)
		(fp_line
			(start -0.120396 0.2794)
			(end 0.12065 0.2794)
			(stroke
				(width 0.1)
				(type default)
			)
			(layer "B.Fab")
		)
		(fp_line
			(start 0.67945 0.3048)
			(end 0.67945 -0.305054)
			(stroke
				(width 0.1)
				(type default)
			)
			(layer "B.Fab")
		)
		(fp_line
			(start 0.12065 0.3048)
			(end 0.67945 0.3048)
			(stroke
				(width 0.1)
				(type default)
			)
			(layer "B.Fab")
		)
		(fp_line
			(start -0.120396 0.3048)
			(end -0.120396 0.2794)
			(stroke
				(width 0.1)
				(type default)
			)
			(layer "B.Fab")
		)
		(fp_line
			(start -0.67945 0.3048)
			(end -0.120396 0.3048)
			(stroke
				(width 0.1)
				(type default)
			)
			(layer "B.Fab")
		)
		(pad "1" smd circle
			(at 0.40005 0 270)
			(size 0 0)
			(layers "B.Cu" "B.Mask" "B.Paste")
			(net "P3V3_OCP_PWRGD_2")
		)
		(pad "2" smd circle
			(at -0.40005 0 270)
			(size 0 0)
			(layers "B.Cu" "B.Mask" "B.Paste")
			(net "OCP_V3_2_P3V3_PWRGD")
		)
	)
	(footprint ""
		(layer "B.Cu")
		(at 407.0731 -317.25108 90)
		(property "Reference" "R3884"
			(at 0 0 90)
			(layer "B.SilkS")
			(hide yes)
			(effects
				(font
					(size 1.27 1.27)
				)
				(justify mirror)
			)
		)
		(property "Value" ""
			(at 0 0 90)
			(layer "B.Fab")
			(effects
				(font
					(size 1.27 1.27)
				)
				(justify mirror)
			)
		)
		(duplicate_pad_numbers_are_jumpers no)
		(fp_line
			(start 0.7874 -0.4064)
			(end -0.7874 -0.4064)
			(stroke
				(width 0.1524)
				(type default)
			)
			(layer "B.SilkS")
		)
		(fp_line
			(start -0.7874 -0.4064)
			(end -0.7874 0.4064)
			(stroke
				(width 0.1524)
				(type default)
			)
			(layer "B.SilkS")
		)
		(fp_line
			(start 0.7874 0.4064)
			(end 0.7874 -0.4064)
			(stroke
				(width 0.1524)
				(type default)
			)
			(layer "B.SilkS")
		)
		(fp_line
			(start -0.7874 0.4064)
			(end 0.7874 0.4064)
			(stroke
				(width 0.1524)
				(type default)
			)
			(layer "B.SilkS")
		)
		(fp_line
			(start 0.67945 -0.305054)
			(end 0.12065 -0.305054)
			(stroke
				(width 0.1)
				(type default)
			)
			(layer "B.Fab")
		)
		(fp_line
			(start 0.12065 -0.305054)
			(end 0.12065 -0.2794)
			(stroke
				(width 0.1)
				(type default)
			)
			(layer "B.Fab")
		)
		(fp_line
			(start -0.12065 -0.3048)
			(end -0.67945 -0.3048)
			(stroke
				(width 0.1)
				(type default)
			)
			(layer "B.Fab")
		)
		(fp_line
			(start -0.67945 -0.3048)
			(end -0.67945 0.3048)
			(stroke
				(width 0.1)
				(type default)
			)
			(layer "B.Fab")
		)
		(fp_line
			(start 0.12065 -0.2794)
			(end -0.12065 -0.2794)
			(stroke
				(width 0.1)
				(type default)
			)
			(layer "B.Fab")
		)
		(fp_line
			(start -0.12065 -0.2794)
			(end -0.12065 -0.3048)
			(stroke
				(width 0.1)
				(type default)
			)
			(layer "B.Fab")
		)
		(fp_line
			(start 0.12065 0.2794)
			(end 0.12065 0.3048)
			(stroke
				(width 0.1)
				(type default)
			)
			(layer "B.Fab")
		)
		(fp_line
			(start -0.120396 0.2794)
			(end 0.12065 0.2794)
			(stroke
				(width 0.1)
				(type default)
			)
			(layer "B.Fab")
		)
		(fp_line
			(start 0.67945 0.3048)
			(end 0.67945 -0.305054)
			(stroke
				(width 0.1)
				(type default)
			)
			(layer "B.Fab")
		)
		(fp_line
			(start 0.12065 0.3048)
			(end 0.67945 0.3048)
			(stroke
				(width 0.1)
				(type default)
			)
			(layer "B.Fab")
		)
		(fp_line
			(start -0.120396 0.3048)
			(end -0.120396 0.2794)
			(stroke
				(width 0.1)
				(type default)
			)
			(layer "B.Fab")
		)
		(fp_line
			(start -0.67945 0.3048)
			(end -0.120396 0.3048)
			(stroke
				(width 0.1)
				(type default)
			)
			(layer "B.Fab")
		)
		(pad "1" smd circle
			(at 0.40005 0 270)
			(size 0 0)
			(layers "B.Cu" "B.Mask" "B.Paste")
			(net "I3C_SPD_DDREFGH_CPU0_LVC1_SCL_1")
		)
		(pad "2" smd circle
			(at -0.40005 0 270)
			(size 0 0)
			(layers "B.Cu" "B.Mask" "B.Paste")
			(net "I3C_SPD_DDREFGH_CPU0_LVC1_SCL")
		)
	)
	(footprint ""
		(layer "B.Cu")
		(at 35.586416 -395.243558 -90)
		(property "Reference" "C2355"
			(at 0 0 90)
			(layer "B.SilkS")
			(hide yes)
			(effects
				(font
					(size 1.27 1.27)
				)
				(justify mirror)
			)
		)
		(property "Value" ""
			(at 0 0 90)
			(layer "B.Fab")
			(effects
				(font
					(size 1.27 1.27)
				)
				(justify mirror)
			)
		)
		(duplicate_pad_numbers_are_jumpers no)
		(fp_line
			(start -0.7874 0.4064)
			(end 0.7874 0.4064)
			(stroke
				(width 0.1524)
				(type default)
			)
			(layer "B.SilkS")
		)
		(fp_line
			(start 0.7874 0.4064)
			(end 0.7874 -0.4064)
			(stroke
				(width 0.1524)
				(type default)
			)
			(layer "B.SilkS")
		)
		(fp_line
			(start -0.7874 -0.4064)
			(end -0.7874 0.4064)
			(stroke
				(width 0.1524)
				(type default)
			)
			(layer "B.SilkS")
		)
		(fp_line
			(start 0.7874 -0.4064)
			(end -0.7874 -0.4064)
			(stroke
				(width 0.1524)
				(type default)
			)
			(layer "B.SilkS")
		)
		(fp_line
			(start -0.67945 0.3048)
			(end -0.120396 0.3048)
			(stroke
				(width 0.1)
				(type default)
			)
			(layer "B.Fab")
		)
		(fp_line
			(start -0.120396 0.3048)
			(end -0.120396 0.2794)
			(stroke
				(width 0.1)
				(type default)
			)
			(layer "B.Fab")
		)
		(fp_line
			(start 0.12065 0.3048)
			(end 0.67945 0.3048)
			(stroke
				(width 0.1)
				(type default)
			)
			(layer "B.Fab")
		)
		(fp_line
			(start 0.67945 0.3048)
			(end 0.67945 -0.305054)
			(stroke
				(width 0.1)
				(type default)
			)
			(layer "B.Fab")
		)
		(fp_line
			(start -0.120396 0.2794)
			(end 0.12065 0.2794)
			(stroke
				(width 0.1)
				(type default)
			)
			(layer "B.Fab")
		)
		(fp_line
			(start 0.12065 0.2794)
			(end 0.12065 0.3048)
			(stroke
				(width 0.1)
				(type default)
			)
			(layer "B.Fab")
		)
		(fp_line
			(start -0.12065 -0.2794)
			(end -0.12065 -0.3048)
			(stroke
				(width 0.1)
				(type default)
			)
			(layer "B.Fab")
		)
		(fp_line
			(start 0.12065 -0.2794)
			(end -0.12065 -0.2794)
			(stroke
				(width 0.1)
				(type default)
			)
			(layer "B.Fab")
		)
		(fp_line
			(start -0.67945 -0.3048)
			(end -0.67945 0.3048)
			(stroke
				(width 0.1)
				(type default)
			)
			(layer "B.Fab")
		)
		(fp_line
			(start -0.12065 -0.3048)
			(end -0.67945 -0.3048)
			(stroke
				(width 0.1)
				(type default)
			)
			(layer "B.Fab")
		)
		(fp_line
			(start 0.12065 -0.305054)
			(end 0.12065 -0.2794)
			(stroke
				(width 0.1)
				(type default)
			)
			(layer "B.Fab")
		)
		(fp_line
			(start 0.67945 -0.305054)
			(end 0.12065 -0.305054)
			(stroke
				(width 0.1)
				(type default)
			)
			(layer "B.Fab")
		)
		(pad "1" smd circle
			(at 0.40005 0 90)
			(size 0 0)
			(layers "B.Cu" "B.Mask" "B.Paste")
			(net "P3V3_AUX")
		)
		(pad "2" smd circle
			(at -0.40005 0 90)
			(size 0 0)
			(layers "B.Cu" "B.Mask" "B.Paste")
			(net "GND")
		)
	)
	(footprint ""
		(layer "B.Cu")
		(at 162.825176 -258.399534 -90)
		(property "Reference" "C479"
			(at 0 0 90)
			(layer "B.SilkS")
			(hide yes)
			(effects
				(font
					(size 1.27 1.27)
				)
				(justify mirror)
			)
		)
		(property "Value" ""
			(at 0 0 90)
			(layer "B.Fab")
			(effects
				(font
					(size 1.27 1.27)
				)
				(justify mirror)
			)
		)
		(duplicate_pad_numbers_are_jumpers no)
		(fp_line
			(start -1.524 0.762)
			(end 1.524 0.762)
			(stroke
				(width 0.1524)
				(type default)
			)
			(layer "B.SilkS")
		)
		(fp_line
			(start 1.524 0.762)
			(end 1.524 -0.762)
			(stroke
				(width 0.1524)
				(type default)
			)
			(layer "B.SilkS")
		)
		(fp_line
			(start -1.524 -0.762)
			(end -1.524 0.762)
			(stroke
				(width 0.1524)
				(type default)
			)
			(layer "B.SilkS")
		)
		(fp_line
			(start 1.524 -0.762)
			(end -1.524 -0.762)
			(stroke
				(width 0.1524)
				(type default)
			)
			(layer "B.SilkS")
		)
		(fp_line
			(start -1.1049 0.724916)
			(end -1.1049 -0.724916)
			(stroke
				(width 0.1)
				(type default)
			)
			(layer "B.Fab")
		)
		(fp_line
			(start 1.1049 0.724916)
			(end -1.1049 0.724916)
			(stroke
				(width 0.1)
				(type default)
			)
			(layer "B.Fab")
		)
		(fp_line
			(start -1.1049 -0.724916)
			(end 1.1049 -0.724916)
			(stroke
				(width 0.1)
				(type default)
			)
			(layer "B.Fab")
		)
		(fp_line
			(start 1.1049 -0.724916)
			(end 1.1049 0.724916)
			(stroke
				(width 0.1)
				(type default)
			)
			(layer "B.Fab")
		)
		(pad "1" smd rect
			(at 0.889 0 270)
			(size 1.016 1.27)
			(layers "B.Cu" "B.Mask" "B.Paste")
			(net "PVCCFA_EHV_FIVRA_CPU1")
		)
		(pad "2" smd rect
			(at -0.889 0 270)
			(size 1.016 1.27)
			(layers "B.Cu" "B.Mask" "B.Paste")
			(net "GND")
		)
	)
)
